(kicad_pcb
	(version 20260206)
	(generator "pcbnew")
	(generator_version "10.0")
	(general
		(thickness 1.6)
		(legacy_teardrops no)
	)
	(paper "A4")
	(title_block
		(title "Bryce Canyon_F.DPB_16315-1-OCP.brd")
		(comment 1 "Bryce Canyon / footprints 142-150 of 2223")
	)
	(layers
		(0 "F.Cu" signal "TOP")
		(4 "In1.Cu" signal "L2GND")
		(6 "In2.Cu" signal "L3")
		(8 "In3.Cu" signal "L4GND")
		(10 "In4.Cu" signal "L5")
		(12 "In5.Cu" signal "L6VCC")
		(14 "In6.Cu" signal "L7VCC")
		(16 "In7.Cu" signal "L8")
		(18 "In8.Cu" signal "L9GND")
		(20 "In9.Cu" signal "L10")
		(22 "In10.Cu" signal "L11GND")
		(2 "B.Cu" signal "BOTTOM")
		(9 "F.Adhes" user "F.Adhesive")
		(11 "B.Adhes" user "B.Adhesive")
		(13 "F.Paste" user "Package Geometry/Pastemask Top")
		(15 "B.Paste" user "Package Geometry/Pastemask Bottom")
		(5 "F.SilkS" user "Ref Des/Silkscreen Top")
		(7 "B.SilkS" user "Ref Des/Silkscreen Bottom")
		(1 "F.Mask" user "Board Geometry/Soldermask Top")
		(3 "B.Mask" user "Board Geometry/Soldermask Bottom")
		(17 "Dwgs.User" user "User.Drawings")
		(19 "Cmts.User" user "User.Comments")
		(21 "Eco1.User" user "User.Eco1")
		(23 "Eco2.User" user "User.Eco2")
		(25 "Edge.Cuts" user "Board Geometry/Outline")
		(27 "Margin" user)
		(31 "F.CrtYd" user "Package Geometry/Place Bound Top")
		(29 "B.CrtYd" user "Package Geometry/Place Bound Bottom")
		(35 "F.Fab" user "Ref Des/Assembly Top")
		(33 "B.Fab" user "Ref Des/Assembly Bottom")
	)
	(footprint ""
		(layer "F.Cu")
		(at 47.853346 -170.609006 90)
		(property "Reference" "C218"
			(at 0 0 90)
			(layer "F.SilkS")
			(hide yes)
			(effects
				(font
					(size 1.27 1.27)
				)
			)
		)
		(property "Value" "SCD033U25V2KX-GP"
			(at 1.1811 -2.7051 90)
			(unlocked yes)
			(layer "F.Fab")
			(hide yes)
			(effects
				(font
					(size 1.016 1.016)
					(thickness 0.1524)
				)
			)
		)
		(property "Device Type" "C402H22"
			(at 1.1811 -4.2291 90)
			(unlocked yes)
			(layer "F.Fab")
			(hide yes)
			(effects
				(font
					(size 1.016 1.016)
					(thickness 0.1524)
				)
			)
		)
		(duplicate_pad_numbers_are_jumpers no)
		(fp_rect
			(start -0.4318 0.9525)
			(end 0.4318 -0.9525)
			(stroke
				(width 0)
				(type default)
			)
			(fill no)
			(layer "F.CrtYd")
		)
		(fp_rect
			(start -0.4318 0.9525)
			(end 0.4318 -0.9525)
			(stroke
				(width 0)
				(type default)
			)
			(fill no)
			(layer "F.Fab")
		)
		(pad "1" smd custom
			(at 0 -0.4445 90)
			(size 0.1524 0.1524)
			(layers "F.Cu" "F.Mask" "F.Paste")
			(net "P12V_A")
			(options
				(clearance outline)
				(anchor circle)
			)
			(primitives
				(gr_poly
					(pts
						(arc
							(start 0.3048 -0.2032)
							(mid 0.275042 -0.275042)
							(end 0.2032 -0.3048)
						)
						(arc
							(start -0.2032 -0.3048)
							(mid -0.275042 -0.275042)
							(end -0.3048 -0.2032)
						)
						(arc
							(start -0.3048 0.2032)
							(mid -0.275042 0.275042)
							(end -0.2032 0.3048)
						)
						(arc
							(start 0.2032 0.3048)
							(mid 0.275042 0.275042)
							(end 0.3048 0.2032)
						)
					)
					(width 0)
					(fill yes)
				)
			)
		)
		(pad "2" smd custom
			(at 0 0.4445 90)
			(size 0.1524 0.1524)
			(layers "F.Cu" "F.Mask" "F.Paste")
			(net "SW_HDD_N13")
			(options
				(clearance outline)
				(anchor circle)
			)
			(primitives
				(gr_poly
					(pts
						(arc
							(start 0.3048 -0.2032)
							(mid 0.275042 -0.275042)
							(end 0.2032 -0.3048)
						)
						(arc
							(start -0.2032 -0.3048)
							(mid -0.275042 -0.275042)
							(end -0.3048 -0.2032)
						)
						(arc
							(start -0.3048 0.2032)
							(mid -0.275042 0.275042)
							(end -0.2032 0.3048)
						)
						(arc
							(start 0.2032 0.3048)
							(mid 0.275042 0.275042)
							(end 0.3048 0.2032)
						)
					)
					(width 0)
					(fill yes)
				)
			)
		)
	)
	(footprint ""
		(layer "F.Cu")
		(at 127.113284 -273.660616 90)
		(property "Reference" "C77"
			(at 0 0 90)
			(layer "F.SilkS")
			(hide yes)
			(effects
				(font
					(size 1.27 1.27)
				)
			)
		)
		(property "Value" "SCD01U16V1KX-GP"
			(at -2.8321 -1.7399 90)
			(unlocked yes)
			(layer "F.Fab")
			(hide yes)
			(effects
				(font
					(size 1.016 1.016)
					(thickness 0.1524)
				)
			)
		)
		(property "Device Type" "C0201H13"
			(at -2.8321 -3.2639 90)
			(unlocked yes)
			(layer "F.Fab")
			(hide yes)
			(effects
				(font
					(size 1.016 1.016)
					(thickness 0.1524)
				)
			)
		)
		(duplicate_pad_numbers_are_jumpers no)
		(fp_rect
			(start -0.2794 0.6477)
			(end 0.2794 -0.6477)
			(stroke
				(width 0)
				(type default)
			)
			(fill no)
			(layer "F.CrtYd")
		)
		(fp_rect
			(start -0.2794 0.6477)
			(end 0.2794 -0.6477)
			(stroke
				(width 0)
				(type default)
			)
			(fill no)
			(layer "F.Fab")
		)
		(pad "1" smd custom
			(at 0 -0.2794 90)
			(size 0.0762 0.0762)
			(layers "F.Cu" "F.Mask" "F.Paste")
			(net "SAS_HDD_RX_P3")
			(options
				(clearance outline)
				(anchor circle)
			)
			(primitives
				(gr_poly
					(pts
						(arc
							(start 0.1524 -0.127)
							(mid 0.137521 -0.162921)
							(end 0.1016 -0.1778)
						)
						(arc
							(start -0.1016 -0.1778)
							(mid -0.137521 -0.162921)
							(end -0.1524 -0.127)
						)
						(arc
							(start -0.1524 0.127)
							(mid -0.137521 0.162921)
							(end -0.1016 0.1778)
						)
						(arc
							(start 0.1016 0.1778)
							(mid 0.137521 0.162921)
							(end 0.1524 0.127)
						)
					)
					(width 0)
					(fill yes)
				)
			)
		)
		(pad "2" smd custom
			(at 0 0.2794 90)
			(size 0.0762 0.0762)
			(layers "F.Cu" "F.Mask" "F.Paste")
			(net "PHY_SCC_A_TO_DRV_A_3_DP")
			(options
				(clearance outline)
				(anchor circle)
			)
			(primitives
				(gr_poly
					(pts
						(arc
							(start 0.1524 -0.127)
							(mid 0.137521 -0.162921)
							(end 0.1016 -0.1778)
						)
						(arc
							(start -0.1016 -0.1778)
							(mid -0.137521 -0.162921)
							(end -0.1524 -0.127)
						)
						(arc
							(start -0.1524 0.127)
							(mid -0.137521 0.162921)
							(end -0.1016 0.1778)
						)
						(arc
							(start 0.1016 0.1778)
							(mid 0.137521 0.162921)
							(end 0.1524 0.127)
						)
					)
					(width 0)
					(fill yes)
				)
			)
		)
	)
	(footprint ""
		(layer "F.Cu")
		(at 426.120052 -73.954894 180)
		(property "Reference" "C473"
			(at 0 0 180)
			(layer "F.SilkS")
			(hide yes)
			(effects
				(font
					(size 1.27 1.27)
				)
			)
		)
		(property "Value" "SC4D7U25V5KX-1-GP"
			(at -0.0762 -6.1214 180)
			(unlocked yes)
			(layer "F.Fab")
			(hide yes)
			(effects
				(font
					(size 1.016 1.016)
					(thickness 0.1524)
				)
			)
		)
		(property "Device Type" "C805H58"
			(at -0.0762 -8.1534 180)
			(unlocked yes)
			(layer "F.Fab")
			(hide yes)
			(effects
				(font
					(size 1.016 1.016)
					(thickness 0.1524)
				)
			)
		)
		(duplicate_pad_numbers_are_jumpers no)
		(fp_line
			(start 0.635 0)
			(end -0.635 0)
			(stroke
				(width 0.508)
				(type default)
			)
			(layer "F.SilkS")
		)
		(fp_rect
			(start -0.9652 1.778)
			(end 0.9652 -1.778)
			(stroke
				(width 0)
				(type default)
			)
			(fill no)
			(layer "F.CrtYd")
		)
		(fp_poly
			(pts
				(xy -0.9652 -1.778) (xy 0.9652 -1.778) (xy 0.9652 1.778) (xy -0.9652 1.778)
			)
			(stroke
				(width 0)
				(type default)
			)
			(fill no)
			(layer "F.Fab")
		)
		(pad "1" smd rect
			(at 0 -0.9652 180)
			(size 1.397 1.143)
			(layers "F.Cu" "F.Mask" "F.Paste")
			(net "P12V_HDD33")
		)
		(pad "2" smd rect
			(at 0 0.9652 180)
			(size 1.397 1.143)
			(layers "F.Cu" "F.Mask" "F.Paste")
			(net "GND")
		)
	)
	(footprint ""
		(layer "F.Cu")
		(at 243.078 -231.14 180)
		(property "Reference" "R85"
			(at 0 0 180)
			(layer "F.SilkS")
			(hide yes)
			(effects
				(font
					(size 1.27 1.27)
				)
			)
		)
		(property "Value" "4K7R2F-GP"
			(at 0.064008 -3.993896 180)
			(unlocked yes)
			(layer "F.Fab")
			(hide yes)
			(effects
				(font
					(size 1.016 1.016)
					(thickness 0.1524)
				)
			)
		)
		(property "Device Type" "R402H16"
			(at 0.064008 -5.517896 180)
			(unlocked yes)
			(layer "F.Fab")
			(hide yes)
			(effects
				(font
					(size 1.016 1.016)
					(thickness 0.1524)
				)
			)
		)
		(duplicate_pad_numbers_are_jumpers no)
		(fp_line
			(start 0.508 -0.9398)
			(end -0.508 -0.9398)
			(stroke
				(width 0.1524)
				(type default)
			)
			(layer "F.SilkS")
		)
		(fp_line
			(start -0.508 -0.9398)
			(end -0.508 0.9398)
			(stroke
				(width 0.1524)
				(type default)
			)
			(layer "F.SilkS")
		)
		(fp_rect
			(start -0.508 0.9398)
			(end 0.508 -0.9398)
			(stroke
				(width 0)
				(type default)
			)
			(fill no)
			(layer "F.CrtYd")
		)
		(fp_rect
			(start -0.508 0.9398)
			(end 0.508 -0.9398)
			(stroke
				(width 0)
				(type default)
			)
			(fill no)
			(layer "F.Fab")
		)
		(pad "1" smd custom
			(at 0 -0.4445 180)
			(size 0.1397 0.1397)
			(layers "F.Cu" "F.Mask" "F.Paste")
			(net "P3V3_STBY_A")
			(options
				(clearance outline)
				(anchor circle)
			)
			(primitives
				(gr_poly
					(pts
						(arc
							(start -0.1778 -0.2794)
							(mid -0.249642 -0.249642)
							(end -0.2794 -0.1778)
						)
						(arc
							(start -0.2794 0.1778)
							(mid -0.249642 0.249642)
							(end -0.1778 0.2794)
						)
						(arc
							(start 0.1778 0.2794)
							(mid 0.249642 0.249642)
							(end 0.2794 0.1778)
						)
						(arc
							(start 0.2794 -0.1778)
							(mid 0.249642 -0.249642)
							(end 0.1778 -0.2794)
						)
					)
					(width 0)
					(fill yes)
				)
			)
		)
		(pad "2" smd custom
			(at 0 0.4445 180)
			(size 0.1397 0.1397)
			(layers "F.Cu" "F.Mask" "F.Paste")
			(net "IO_EXP2_A1")
			(options
				(clearance outline)
				(anchor circle)
			)
			(primitives
				(gr_poly
					(pts
						(arc
							(start -0.1778 -0.2794)
							(mid -0.249642 -0.249642)
							(end -0.2794 -0.1778)
						)
						(arc
							(start -0.2794 0.1778)
							(mid -0.249642 0.249642)
							(end -0.1778 0.2794)
						)
						(arc
							(start 0.1778 0.2794)
							(mid 0.249642 0.249642)
							(end 0.2794 0.1778)
						)
						(arc
							(start 0.2794 -0.1778)
							(mid 0.249642 -0.249642)
							(end 0.1778 -0.2794)
						)
					)
					(width 0)
					(fill yes)
				)
			)
		)
	)
	(footprint ""
		(layer "F.Cu")
		(at 193.2686 -298.704)
		(property "Reference" "TP27"
			(at 0 0 0)
			(layer "F.SilkS")
			(hide yes)
			(effects
				(font
					(size 1.27 1.27)
				)
			)
		)
		(property "Value" "TPAD32-GP"
			(at -0.0508 -1.6764 0)
			(unlocked yes)
			(layer "F.Fab")
			(hide yes)
			(effects
				(font
					(size 1.016 1.016)
					(thickness 0.1524)
				)
			)
		)
		(property "Device Type" "TPAD32"
			(at -0.0508 -3.2004 0)
			(unlocked yes)
			(layer "F.Fab")
			(hide yes)
			(effects
				(font
					(size 1.016 1.016)
					(thickness 0.1524)
				)
			)
		)
		(duplicate_pad_numbers_are_jumpers no)
		(fp_poly
			(pts
				(arc
					(start 0.4064 0)
					(mid -0.4064 0)
					(end 0.4064 0)
				)
			)
			(stroke
				(width 0)
				(type default)
			)
			(fill no)
			(layer "F.CrtYd")
		)
		(fp_poly
			(pts
				(arc
					(start 0.7112 0)
					(mid -0.7112 0)
					(end 0.7112 0)
				)
			)
			(stroke
				(width 0)
				(type default)
			)
			(fill no)
			(layer "F.Fab")
		)
		(pad "1" smd circle
			(at 0 0)
			(size 0.8128 0.8128)
			(layers "F.Cu" "F.Mask" "F.Paste")
			(net "ACT_HDD_5")
		)
	)
	(footprint ""
		(layer "F.Cu")
		(at 158.708852 -47.749968 -90)
		(property "Reference" "VIA64"
			(at 0 0 270)
			(layer "F.SilkS")
			(hide yes)
			(effects
				(font
					(size 1.27 1.27)
				)
			)
		)
		(property "Value" "100OHM-8L-1D6MM-L18L16-GP"
			(at -3.7211 -4.5085 270)
			(unlocked yes)
			(layer "F.Fab")
			(hide yes)
			(effects
				(font
					(size 1.016 1.016)
					(thickness 0.1524)
				)
			)
		)
		(property "Device Type" "VIA-PCIE-4P-394076"
			(at -3.7211 -6.0325 270)
			(unlocked yes)
			(layer "F.Fab")
			(hide yes)
			(effects
				(font
					(size 1.016 1.016)
					(thickness 0.1524)
				)
			)
		)
		(duplicate_pad_numbers_are_jumpers no)
		(fp_rect
			(start -1.9685 0.381)
			(end 1.9685 -0.381)
			(stroke
				(width 0)
				(type default)
			)
			(fill no)
			(layer "F.CrtYd")
		)
		(fp_rect
			(start -1.9685 0.381)
			(end 1.9685 -0.381)
			(stroke
				(width 0)
				(type default)
			)
			(fill no)
			(layer "F.Fab")
		)
		(pad "1" thru_hole circle
			(at -1.5875 0 270)
			(size 0.508 0.508)
			(drill 0.254)
			(layers "*.Cu" "*.Mask")
			(remove_unused_layers no)
			(net "GND")
			(clearance 0.127)
			(thermal_gap 0.127)
		)
		(pad "2" thru_hole circle
			(at -0.5715 0 270)
			(size 0.508 0.508)
			(drill 0.254)
			(layers "*.Cu" "*.Mask")
			(remove_unused_layers no)
			(net "PHY_DRV_A_TO_SCC_A_28_DP")
			(clearance 0.127)
			(thermal_gap 0.127)
		)
		(pad "3" thru_hole circle
			(at 0.5715 0 270)
			(size 0.508 0.508)
			(drill 0.254)
			(layers "*.Cu" "*.Mask")
			(remove_unused_layers no)
			(net "PHY_DRV_A_TO_SCC_A_28_DN")
			(clearance 0.127)
			(thermal_gap 0.127)
		)
		(pad "4" thru_hole circle
			(at 1.5875 0 270)
			(size 0.508 0.508)
			(drill 0.254)
			(layers "*.Cu" "*.Mask")
			(remove_unused_layers no)
			(net "GND")
			(clearance 0.127)
			(thermal_gap 0.127)
		)
	)
	(footprint ""
		(layer "F.Cu")
		(at 143.049498 -167.060118 90)
		(property "Reference" "R505"
			(at 0 0 90)
			(layer "F.SilkS")
			(hide yes)
			(effects
				(font
					(size 1.27 1.27)
				)
			)
		)
		(property "Value" "4K7R2J-2-GP"
			(at 0.064008 -3.993896 90)
			(unlocked yes)
			(layer "F.Fab")
			(hide yes)
			(effects
				(font
					(size 1.016 1.016)
					(thickness 0.1524)
				)
			)
		)
		(property "Device Type" "R402H16"
			(at 0.064008 -5.517896 90)
			(unlocked yes)
			(layer "F.Fab")
			(hide yes)
			(effects
				(font
					(size 1.016 1.016)
					(thickness 0.1524)
				)
			)
		)
		(duplicate_pad_numbers_are_jumpers no)
		(fp_line
			(start 0.508 -0.9398)
			(end -0.508 -0.9398)
			(stroke
				(width 0.1524)
				(type default)
			)
			(layer "F.SilkS")
		)
		(fp_line
			(start -0.508 -0.9398)
			(end -0.508 0.9398)
			(stroke
				(width 0.1524)
				(type default)
			)
			(layer "F.SilkS")
		)
		(fp_rect
			(start -0.508 0.9398)
			(end 0.508 -0.9398)
			(stroke
				(width 0)
				(type default)
			)
			(fill no)
			(layer "F.CrtYd")
		)
		(fp_rect
			(start -0.508 0.9398)
			(end 0.508 -0.9398)
			(stroke
				(width 0)
				(type default)
			)
			(fill no)
			(layer "F.Fab")
		)
		(pad "1" smd custom
			(at 0 -0.4445 90)
			(size 0.1397 0.1397)
			(layers "F.Cu" "F.Mask" "F.Paste")
			(net "P12V_A")
			(options
				(clearance outline)
				(anchor circle)
			)
			(primitives
				(gr_poly
					(pts
						(arc
							(start -0.1778 -0.2794)
							(mid -0.249642 -0.249642)
							(end -0.2794 -0.1778)
						)
						(arc
							(start -0.2794 0.1778)
							(mid -0.249642 0.249642)
							(end -0.1778 0.2794)
						)
						(arc
							(start 0.1778 0.2794)
							(mid 0.249642 0.249642)
							(end 0.2794 0.1778)
						)
						(arc
							(start 0.2794 -0.1778)
							(mid 0.249642 -0.249642)
							(end 0.1778 -0.2794)
						)
					)
					(width 0)
					(fill yes)
				)
			)
		)
		(pad "2" smd custom
			(at 0 0.4445 90)
			(size 0.1397 0.1397)
			(layers "F.Cu" "F.Mask" "F.Paste")
			(net "SW_HDD_P16")
			(options
				(clearance outline)
				(anchor circle)
			)
			(primitives
				(gr_poly
					(pts
						(arc
							(start -0.1778 -0.2794)
							(mid -0.249642 -0.249642)
							(end -0.2794 -0.1778)
						)
						(arc
							(start -0.2794 0.1778)
							(mid -0.249642 0.249642)
							(end -0.1778 0.2794)
						)
						(arc
							(start 0.1778 0.2794)
							(mid 0.249642 0.249642)
							(end 0.2794 0.1778)
						)
						(arc
							(start 0.2794 -0.1778)
							(mid 0.249642 -0.249642)
							(end 0.1778 -0.2794)
						)
					)
					(width 0)
					(fill yes)
				)
			)
		)
	)
	(footprint ""
		(layer "F.Cu")
		(at 332.74 -49.596294 90)
		(property "Reference" "C438"
			(at 0 0 90)
			(layer "F.SilkS")
			(hide yes)
			(effects
				(font
					(size 1.27 1.27)
				)
			)
		)
		(property "Value" "SCD033U25V2KX-GP"
			(at 1.1811 -2.7051 90)
			(unlocked yes)
			(layer "F.Fab")
			(hide yes)
			(effects
				(font
					(size 1.016 1.016)
					(thickness 0.1524)
				)
			)
		)
		(property "Device Type" "C402H22"
			(at 1.1811 -4.2291 90)
			(unlocked yes)
			(layer "F.Fab")
			(hide yes)
			(effects
				(font
					(size 1.016 1.016)
					(thickness 0.1524)
				)
			)
		)
		(duplicate_pad_numbers_are_jumpers no)
		(fp_rect
			(start -0.4318 0.9525)
			(end 0.4318 -0.9525)
			(stroke
				(width 0)
				(type default)
			)
			(fill no)
			(layer "F.CrtYd")
		)
		(fp_rect
			(start -0.4318 0.9525)
			(end 0.4318 -0.9525)
			(stroke
				(width 0)
				(type default)
			)
			(fill no)
			(layer "F.Fab")
		)
		(pad "1" smd custom
			(at 0 -0.4445 90)
			(size 0.1524 0.1524)
			(layers "F.Cu" "F.Mask" "F.Paste")
			(net "SW_HDD_P30")
			(options
				(clearance outline)
				(anchor circle)
			)
			(primitives
				(gr_poly
					(pts
						(arc
							(start 0.3048 -0.2032)
							(mid 0.275042 -0.275042)
							(end 0.2032 -0.3048)
						)
						(arc
							(start -0.2032 -0.3048)
							(mid -0.275042 -0.275042)
							(end -0.3048 -0.2032)
						)
						(arc
							(start -0.3048 0.2032)
							(mid -0.275042 0.275042)
							(end -0.2032 0.3048)
						)
						(arc
							(start 0.2032 0.3048)
							(mid 0.275042 0.275042)
							(end 0.3048 0.2032)
						)
					)
					(width 0)
					(fill yes)
				)
			)
		)
		(pad "2" smd custom
			(at 0 0.4445 90)
			(size 0.1524 0.1524)
			(layers "F.Cu" "F.Mask" "F.Paste")
			(net "GND")
			(options
				(clearance outline)
				(anchor circle)
			)
			(primitives
				(gr_poly
					(pts
						(arc
							(start 0.3048 -0.2032)
							(mid 0.275042 -0.275042)
							(end 0.2032 -0.3048)
						)
						(arc
							(start -0.2032 -0.3048)
							(mid -0.275042 -0.275042)
							(end -0.3048 -0.2032)
						)
						(arc
							(start -0.3048 0.2032)
							(mid -0.275042 0.275042)
							(end -0.2032 0.3048)
						)
						(arc
							(start 0.2032 0.3048)
							(mid 0.275042 0.275042)
							(end 0.3048 0.2032)
						)
					)
					(width 0)
					(fill yes)
				)
			)
		)
	)
	(footprint ""
		(layer "F.Cu")
		(at 396.34795 -272.585942 180)
		(property "Reference" "R322"
			(at 0 0 180)
			(layer "F.SilkS")
			(hide yes)
			(effects
				(font
					(size 1.27 1.27)
				)
			)
		)
		(property "Value" "1KR2F-3-GP"
			(at 0.064008 -3.993896 180)
			(unlocked yes)
			(layer "F.Fab")
			(hide yes)
			(effects
				(font
					(size 1.016 1.016)
					(thickness 0.1524)
				)
			)
		)
		(property "Device Type" "R402H16"
			(at 0.064008 -5.517896 180)
			(unlocked yes)
			(layer "F.Fab")
			(hide yes)
			(effects
				(font
					(size 1.016 1.016)
					(thickness 0.1524)
				)
			)
		)
		(duplicate_pad_numbers_are_jumpers no)
		(fp_line
			(start 0.508 -0.9398)
			(end -0.508 -0.9398)
			(stroke
				(width 0.1524)
				(type default)
			)
			(layer "F.SilkS")
		)
		(fp_line
			(start -0.508 -0.9398)
			(end -0.508 0.9398)
			(stroke
				(width 0.1524)
				(type default)
			)
			(layer "F.SilkS")
		)
		(fp_rect
			(start -0.508 0.9398)
			(end 0.508 -0.9398)
			(stroke
				(width 0)
				(type default)
			)
			(fill no)
			(layer "F.CrtYd")
		)
		(fp_rect
			(start -0.508 0.9398)
			(end 0.508 -0.9398)
			(stroke
				(width 0)
				(type default)
			)
			(fill no)
			(layer "F.Fab")
		)
		(pad "1" smd custom
			(at 0 -0.4445 180)
			(size 0.1397 0.1397)
			(layers "F.Cu" "F.Mask" "F.Paste")
			(net "P3V3_STBY_A")
			(options
				(clearance outline)
				(anchor circle)
			)
			(primitives
				(gr_poly
					(pts
						(arc
							(start -0.1778 -0.2794)
							(mid -0.249642 -0.249642)
							(end -0.2794 -0.1778)
						)
						(arc
							(start -0.2794 0.1778)
							(mid -0.249642 0.249642)
							(end -0.1778 0.2794)
						)
						(arc
							(start 0.1778 0.2794)
							(mid 0.249642 0.249642)
							(end 0.2794 0.1778)
						)
						(arc
							(start 0.2794 -0.1778)
							(mid 0.249642 -0.249642)
							(end 0.1778 -0.2794)
						)
					)
					(width 0)
					(fill yes)
				)
			)
		)
		(pad "2" smd custom
			(at 0 0.4445 180)
			(size 0.1397 0.1397)
			(layers "F.Cu" "F.Mask" "F.Paste")
			(net "SW_PWR_R_HDD8")
			(options
				(clearance outline)
				(anchor circle)
			)
			(primitives
				(gr_poly
					(pts
						(arc
							(start -0.1778 -0.2794)
							(mid -0.249642 -0.249642)
							(end -0.2794 -0.1778)
						)
						(arc
							(start -0.2794 0.1778)
							(mid -0.249642 0.249642)
							(end -0.1778 0.2794)
						)
						(arc
							(start 0.1778 0.2794)
							(mid 0.249642 0.249642)
							(end 0.2794 0.1778)
						)
						(arc
							(start 0.2794 -0.1778)
							(mid 0.249642 -0.249642)
							(end 0.1778 -0.2794)
						)
					)
					(width 0)
					(fill yes)
				)
			)
		)
	)
)
